# BASEBOARD_FAB2 (Tioga Pass) — schematic netlist excerpt (pin names and nets, part order shuffled) for the footprints in the layout excerpt that follows; sources: Cadence DE-HDL packaged netlist, KiCad conversion of Wiwynn_Tioga_Pass_MB.brd

R4A5  RES  10.0K 1% CHIP  pkg 0402  page 230 : A = P3V3 ; B = PWRGD_PVTT_KLM_CPU1_R
R12W17  665KR5B-1-GP  0.1%  pkg SMD-RG3  page 197 : \1\ = P12V_NVDIMM_KLM_D ; \2\ = VR_PVDDQ_KLM_VINSEN
R9G17  RES  0.0 5% CHIP  pkg 0402  page 141 : A = NIC_SET_N_MDI_2_DN ; B = NIC_MDI_SPRV_RJ45_2_R_DN

(kicad_pcb
	(version 20260206)
	(generator "pcbnew")
	(generator_version "10.0")
	(general
		(thickness 1.6)
		(legacy_teardrops no)
	)
	(paper "A4")
	(title_block
		(title "Wiwynn_Tioga_Pass_MB.brd")
		(comment 1 "Tioga Pass / footprints 1394-1396 of 4770")
	)
	(layers
		(0 "F.Cu" signal "TOP")
		(4 "In1.Cu" signal "L2GND")
		(6 "In2.Cu" signal "L3")
		(8 "In3.Cu" signal "L4GND")
		(10 "In4.Cu" signal "L5")
		(12 "In5.Cu" signal "L6GND")
		(14 "In6.Cu" signal "L7VCC")
		(16 "In7.Cu" signal "L8VCC")
		(18 "In8.Cu" signal "L9GND")
		(20 "In9.Cu" signal "L10")
		(22 "In10.Cu" signal "L11GND")
		(24 "In11.Cu" signal "L12")
		(26 "In12.Cu" signal "L13GND")
		(2 "B.Cu" signal "BOTTOM")
		(9 "F.Adhes" user "F.Adhesive")
		(11 "B.Adhes" user "B.Adhesive")
		(13 "F.Paste" user "Package Geometry/Pastemask Top")
		(15 "B.Paste" user "Package Geometry/Pastemask Bottom")
		(5 "F.SilkS" user "Ref Des/Silkscreen Top")
		(7 "B.SilkS" user "Ref Des/Silkscreen Bottom")
		(1 "F.Mask" user "Board Geometry/Soldermask Top")
		(3 "B.Mask" user "Board Geometry/Soldermask Bottom")
		(17 "Dwgs.User" user "User.Drawings")
		(19 "Cmts.User" user "User.Comments")
		(21 "Eco1.User" user "User.Eco1")
		(23 "Eco2.User" user "User.Eco2")
		(25 "Edge.Cuts" user "Board Geometry/Outline")
		(27 "Margin" user)
		(31 "F.CrtYd" user "Package Geometry/Place Bound Top")
		(29 "B.CrtYd" user "Package Geometry/Place Bound Bottom")
		(35 "F.Fab" user "Ref Des/Assembly Top")
		(33 "B.Fab" user "Ref Des/Assembly Bottom")
	)
	(footprint ""
		(layer "F.Cu")
		(at 10.166096 -124.854208 -90)
		(property "Reference" "R12W17"
			(at 0 0 270)
			(layer "F.SilkS")
			(hide yes)
			(effects
				(font
					(size 1.27 1.27)
				)
			)
		)
		(property "Value" "*"
			(at 0 -8.9535 270)
			(unlocked yes)
			(layer "F.Fab")
			(hide yes)
			(effects
				(font
					(size 1.27 1.016)
					(thickness 0.1524)
				)
			)
		)
		(property "Device Type" "665KR5B-1-GP_SMD-RG3-665KR5B-1A"
			(at 0 -10.6299 270)
			(unlocked yes)
			(layer "F.Fab")
			(hide yes)
			(effects
				(font
					(size 1.27 1.016)
					(thickness 0.1524)
				)
			)
		)
		(duplicate_pad_numbers_are_jumpers no)
		(fp_line
			(start -0.889 1.7018)
			(end 0.889 1.7018)
			(stroke
				(width 0.1524)
				(type default)
			)
			(layer "F.SilkS")
		)
		(fp_line
			(start 0.889 1.7018)
			(end 0.889 -0.508)
			(stroke
				(width 0.1524)
				(type default)
			)
			(layer "F.SilkS")
		)
		(fp_line
			(start -0.889 0.0762)
			(end -0.889 1.7018)
			(stroke
				(width 0.1524)
				(type default)
			)
			(layer "F.SilkS")
		)
		(fp_line
			(start -0.889 -1.7018)
			(end -0.889 0.2794)
			(stroke
				(width 0.1524)
				(type default)
			)
			(layer "F.SilkS")
		)
		(fp_line
			(start 0.889 -1.7018)
			(end 0.889 -0.381)
			(stroke
				(width 0.1524)
				(type default)
			)
			(layer "F.SilkS")
		)
		(fp_line
			(start 0.889 -1.7018)
			(end -0.889 -1.7018)
			(stroke
				(width 0.1524)
				(type default)
			)
			(layer "F.SilkS")
		)
		(fp_poly
			(pts
				(xy 0.9652 -1.778) (xy 0.9652 1.778) (xy -0.9652 1.778) (xy -0.9652 -1.778)
			)
			(stroke
				(width 0)
				(type default)
			)
			(fill no)
			(layer "F.CrtYd")
		)
		(fp_rect
			(start -0.9652 1.778)
			(end 0.9652 -1.778)
			(stroke
				(width 0)
				(type default)
			)
			(fill no)
			(layer "F.Fab")
		)
		(pad "1" smd rect
			(at 0 -0.9652 270)
			(size 1.397 1.143)
			(layers "F.Cu" "F.Mask" "F.Paste")
			(net "P12V_NVDIMM_KLM_D")
		)
		(pad "2" smd rect
			(at 0 0.9652 270)
			(size 1.397 1.143)
			(layers "F.Cu" "F.Mask" "F.Paste")
			(net "VR_PVDDQ_KLM_VINSEN")
		)
	)
	(footprint ""
		(layer "F.Cu")
		(at 480.845876 3.820668 -90)
		(property "Reference" "R9G17"
			(at 0 0 270)
			(layer "F.SilkS")
			(hide yes)
			(effects
				(font
					(size 1.27 1.27)
				)
			)
		)
		(property "Value" ""
			(at 0 0 270)
			(layer "F.Fab")
			(effects
				(font
					(size 1.27 1.27)
				)
			)
		)
		(duplicate_pad_numbers_are_jumpers no)
		(fp_poly
			(pts
				(xy -0.2794 -0.1016) (xy 0.2794 -0.1016) (xy 0.2794 0.9906) (xy -0.2794 0.9906)
			)
			(stroke
				(width 0)
				(type default)
			)
			(fill no)
			(layer "F.CrtYd")
		)
		(fp_line
			(start -0.2794 0.9906)
			(end 0.2794 0.9906)
			(stroke
				(width 0.1)
				(type default)
			)
			(layer "F.Fab")
		)
		(fp_line
			(start 0.2794 0.9906)
			(end 0.2794 -0.1016)
			(stroke
				(width 0.1)
				(type default)
			)
			(layer "F.Fab")
		)
		(fp_line
			(start -0.2794 -0.1016)
			(end -0.2794 0.9906)
			(stroke
				(width 0.1)
				(type default)
			)
			(layer "F.Fab")
		)
		(fp_line
			(start 0.2794 -0.1016)
			(end -0.2794 -0.1016)
			(stroke
				(width 0.1)
				(type default)
			)
			(layer "F.Fab")
		)
		(pad "1" smd rect
			(at 0 0 270)
			(size 0.508 0.508)
			(layers "F.Cu" "F.Mask" "F.Paste")
			(net "NIC_SET_N_MDI_2_DN")
		)
		(pad "2" smd rect
			(at 0 0.889 270)
			(size 0.508 0.508)
			(layers "F.Cu" "F.Mask" "F.Paste")
			(net "NIC_MDI_SPRV_RJ45_2_R_DN")
		)
		(zone
			(layer "F.Cu")
			(hatch none 0.5)
			(connect_pads
				(clearance 0)
			)
			(min_thickness 0.25)
			(keepout
				(tracks not_allowed)
				(vias allowed)
				(pads allowed)
				(copperpour not_allowed)
				(footprints allowed)
			)
			(placement
				(enabled no)
				(sheetname "")
			)
			(fill
				(thermal_gap 0.5)
				(thermal_bridge_width 0.5)
				(island_removal_mode 0)
			)
			(polygon
				(pts
					(xy 480.210876 3.566668) (xy 480.210876 4.074668) (xy 480.591876 4.074668) (xy 480.591876 3.566668)
				)
			)
		)
		(zone
			(layer "F.Cu")
			(hatch none 0.5)
			(connect_pads
				(clearance 0)
			)
			(min_thickness 0.25)
			(keepout
				(tracks allowed)
				(vias not_allowed)
				(pads allowed)
				(copperpour not_allowed)
				(footprints allowed)
			)
			(placement
				(enabled no)
				(sheetname "")
			)
			(fill
				(thermal_gap 0.5)
				(thermal_bridge_width 0.5)
				(island_removal_mode 0)
			)
			(polygon
				(pts
					(xy 480.591876 3.566668) (xy 480.591876 4.074668) (xy 480.210876 4.074668) (xy 480.210876 3.566668)
				)
			)
		)
	)
	(footprint ""
		(layer "F.Cu")
		(at 175.26 -149.3012 -90)
		(property "Reference" "R4A5"
			(at 0 0 270)
			(layer "F.SilkS")
			(hide yes)
			(effects
				(font
					(size 1.27 1.27)
				)
			)
		)
		(property "Value" ""
			(at 0 0 270)
			(layer "F.Fab")
			(effects
				(font
					(size 1.27 1.27)
				)
			)
		)
		(duplicate_pad_numbers_are_jumpers no)
		(fp_rect
			(start 0.2794 -0.1016)
			(end -0.2794 0.9906)
			(stroke
				(width 0)
				(type default)
			)
			(fill no)
			(layer "F.CrtYd")
		)
		(fp_line
			(start -0.2794 0.9906)
			(end 0.2794 0.9906)
			(stroke
				(width 0.1)
				(type default)
			)
			(layer "F.Fab")
		)
		(fp_line
			(start 0.2794 0.9906)
			(end 0.2794 -0.1016)
			(stroke
				(width 0.1)
				(type default)
			)
			(layer "F.Fab")
		)
		(fp_line
			(start -0.2794 -0.1016)
			(end -0.2794 0.9906)
			(stroke
				(width 0.1)
				(type default)
			)
			(layer "F.Fab")
		)
		(fp_line
			(start 0.2794 -0.1016)
			(end -0.2794 -0.1016)
			(stroke
				(width 0.1)
				(type default)
			)
			(layer "F.Fab")
		)
		(pad "1" smd rect
			(at 0 0 270)
			(size 0.508 0.508)
			(layers "F.Cu" "F.Mask" "F.Paste")
			(net "P3V3")
		)
		(pad "2" smd rect
			(at 0 0.889 270)
			(size 0.508 0.508)
			(layers "F.Cu" "F.Mask" "F.Paste")
			(net "PWRGD_PVTT_KLM_CPU1_R")
		)
		(zone
			(layer "F.Cu")
			(hatch none 0.5)
			(connect_pads
				(clearance 0)
			)
			(min_thickness 0.25)
			(keepout
				(tracks not_allowed)
				(vias allowed)
				(pads allowed)
				(copperpour not_allowed)
				(footprints allowed)
			)
			(placement
				(enabled no)
				(sheetname "")
			)
			(fill
				(thermal_gap 0.5)
				(thermal_bridge_width 0.5)
				(island_removal_mode 0)
			)
			(polygon
				(pts
					(xy 175.006 -149.0472) (xy 175.006 -149.5552) (xy 174.625 -149.5552) (xy 174.625 -149.0472)
				)
			)
		)
		(zone
			(layer "F.Cu")
			(hatch none 0.5)
			(connect_pads
				(clearance 0)
			)
			(min_thickness 0.25)
			(keepout
				(tracks allowed)
				(vias not_allowed)
				(pads allowed)
				(copperpour not_allowed)
				(footprints allowed)
			)
			(placement
				(enabled no)
				(sheetname "")
			)
			(fill
				(thermal_gap 0.5)
				(thermal_bridge_width 0.5)
				(island_removal_mode 0)
			)
			(polygon
				(pts
					(xy 175.006 -149.0472) (xy 175.006 -149.5552) (xy 174.625 -149.5552) (xy 174.625 -149.0472)
				)
			)
		)
	)
)
